(kicad_pcb
	(version 20260206)
	(generator "pcbnew")
	(generator_version "10.0")
	(general
		(thickness 1.6)
		(legacy_teardrops no)
	)
	(paper "A4")
	(title_block
		(title "01162023_DA0F0TEBIF0_F0T_Expander_BD_F_brd_V02_OCP.brd")
		(comment 1 "Grand Teton / footprints 4076-4084 of 9728")
	)
	(layers
		(0 "F.Cu" signal "TOP")
		(4 "In1.Cu" signal "GND")
		(6 "In2.Cu" signal "VCC")
		(8 "In3.Cu" signal "VCC1")
		(10 "In4.Cu" signal "GND1")
		(12 "In5.Cu" signal "IN1")
		(14 "In6.Cu" signal "GND2")
		(16 "In7.Cu" signal "IN2")
		(18 "In8.Cu" signal "GND3")
		(20 "In9.Cu" signal "IN3")
		(22 "In10.Cu" signal "GND4")
		(24 "In11.Cu" signal "IN4")
		(26 "In12.Cu" signal "GND5")
		(28 "In13.Cu" signal "IN5")
		(30 "In14.Cu" signal "GND6")
		(32 "In15.Cu" signal "IN6")
		(34 "In16.Cu" signal "GND7")
		(2 "B.Cu" signal "BOTTOM")
		(9 "F.Adhes" user "F.Adhesive")
		(11 "B.Adhes" user "B.Adhesive")
		(13 "F.Paste" user "Package Geometry/Pastemask Top")
		(15 "B.Paste" user "Package Geometry/Pastemask Bottom")
		(5 "F.SilkS" user "Ref Des/Silkscreen Top")
		(7 "B.SilkS" user "Ref Des/Silkscreen Bottom")
		(1 "F.Mask" user "Board Geometry/Soldermask Top")
		(3 "B.Mask" user "Board Geometry/Soldermask Bottom")
		(17 "Dwgs.User" user "User.Drawings")
		(19 "Cmts.User" user "User.Comments")
		(21 "Eco1.User" user "User.Eco1")
		(23 "Eco2.User" user "User.Eco2")
		(25 "Edge.Cuts" user "Board Geometry/Outline")
		(27 "Margin" user)
		(31 "F.CrtYd" user "Package Geometry/Place Bound Top")
		(29 "B.CrtYd" user "Package Geometry/Place Bound Bottom")
		(35 "F.Fab" user "Ref Des/Assembly Top")
		(33 "B.Fab" user "Ref Des/Assembly Bottom")
	)
	(footprint ""
		(layer "F.Cu")
		(at 336.443574 -46.90491)
		(property "Reference" "R629"
			(at 0 0 0)
			(layer "F.SilkS")
			(hide yes)
			(effects
				(font
					(size 1.27 1.27)
				)
			)
		)
		(property "Value" ""
			(at 0 0 0)
			(layer "F.Fab")
			(effects
				(font
					(size 1.27 1.27)
				)
			)
		)
		(duplicate_pad_numbers_are_jumpers no)
		(fp_line
			(start -0.7874 -0.4064)
			(end 0.7874 -0.4064)
			(stroke
				(width 0.1524)
				(type default)
			)
			(layer "F.SilkS")
		)
		(fp_line
			(start -0.7874 0.4064)
			(end -0.7874 -0.4064)
			(stroke
				(width 0.1524)
				(type default)
			)
			(layer "F.SilkS")
		)
		(fp_line
			(start 0.7874 -0.4064)
			(end 0.7874 0.4064)
			(stroke
				(width 0.1524)
				(type default)
			)
			(layer "F.SilkS")
		)
		(fp_line
			(start 0.7874 0.4064)
			(end -0.7874 0.4064)
			(stroke
				(width 0.1524)
				(type default)
			)
			(layer "F.SilkS")
		)
		(fp_line
			(start -0.67945 -0.305054)
			(end -0.12065 -0.305054)
			(stroke
				(width 0.1)
				(type default)
			)
			(layer "F.Fab")
		)
		(fp_line
			(start -0.67945 0.3048)
			(end -0.67945 -0.305054)
			(stroke
				(width 0.1)
				(type default)
			)
			(layer "F.Fab")
		)
		(fp_line
			(start -0.12065 -0.305054)
			(end -0.12065 -0.2794)
			(stroke
				(width 0.1)
				(type default)
			)
			(layer "F.Fab")
		)
		(fp_line
			(start -0.12065 -0.2794)
			(end 0.12065 -0.2794)
			(stroke
				(width 0.1)
				(type default)
			)
			(layer "F.Fab")
		)
		(fp_line
			(start -0.12065 0.2794)
			(end -0.12065 0.3048)
			(stroke
				(width 0.1)
				(type default)
			)
			(layer "F.Fab")
		)
		(fp_line
			(start -0.12065 0.3048)
			(end -0.67945 0.3048)
			(stroke
				(width 0.1)
				(type default)
			)
			(layer "F.Fab")
		)
		(fp_line
			(start 0.120396 0.2794)
			(end -0.12065 0.2794)
			(stroke
				(width 0.1)
				(type default)
			)
			(layer "F.Fab")
		)
		(fp_line
			(start 0.120396 0.3048)
			(end 0.120396 0.2794)
			(stroke
				(width 0.1)
				(type default)
			)
			(layer "F.Fab")
		)
		(fp_line
			(start 0.12065 -0.3048)
			(end 0.67945 -0.3048)
			(stroke
				(width 0.1)
				(type default)
			)
			(layer "F.Fab")
		)
		(fp_line
			(start 0.12065 -0.2794)
			(end 0.12065 -0.3048)
			(stroke
				(width 0.1)
				(type default)
			)
			(layer "F.Fab")
		)
		(fp_line
			(start 0.67945 -0.3048)
			(end 0.67945 0.3048)
			(stroke
				(width 0.1)
				(type default)
			)
			(layer "F.Fab")
		)
		(fp_line
			(start 0.67945 0.3048)
			(end 0.120396 0.3048)
			(stroke
				(width 0.1)
				(type default)
			)
			(layer "F.Fab")
		)
		(pad "1" smd circle
			(at -0.40005 0)
			(size 0 0)
			(layers "F.Cu" "F.Mask" "F.Paste")
			(net "SSD11_ADC_ALERT_N")
		)
		(pad "2" smd circle
			(at 0.40005 0)
			(size 0 0)
			(layers "F.Cu" "F.Mask" "F.Paste")
			(net "SSD_8_15_ADC_ALERT_N")
		)
	)
	(footprint ""
		(layer "F.Cu")
		(at 178.619912 -356.244906 90)
		(property "Reference" "C2529"
			(at 0 0 90)
			(layer "F.SilkS")
			(hide yes)
			(effects
				(font
					(size 1.27 1.27)
				)
			)
		)
		(property "Value" ""
			(at 0 0 90)
			(layer "F.Fab")
			(effects
				(font
					(size 1.27 1.27)
				)
			)
		)
		(duplicate_pad_numbers_are_jumpers no)
		(fp_line
			(start 0.299974 -0.150114)
			(end 0.299974 0.150114)
			(stroke
				(width 0.1)
				(type default)
			)
			(layer "F.Fab")
		)
		(fp_line
			(start -0.299974 -0.150114)
			(end 0.299974 -0.150114)
			(stroke
				(width 0.1)
				(type default)
			)
			(layer "F.Fab")
		)
		(fp_line
			(start 0.299974 0.150114)
			(end -0.299974 0.150114)
			(stroke
				(width 0.1)
				(type default)
			)
			(layer "F.Fab")
		)
		(fp_line
			(start -0.299974 0.150114)
			(end -0.299974 -0.150114)
			(stroke
				(width 0.1)
				(type default)
			)
			(layer "F.Fab")
		)
		(pad "1" smd rect
			(at -0.2667 0 90)
			(size 0.3048 0.381)
			(layers "F.Cu" "F.Mask" "F.Paste")
			(net "P5E_PEX1_STN4_TX_DN<71>")
		)
		(pad "2" smd rect
			(at 0.2667 0 90)
			(size 0.3048 0.381)
			(layers "F.Cu" "F.Mask" "F.Paste")
			(net "P5E_PEX1_STN4_TX_C_DN<71>")
		)
	)
	(footprint ""
		(layer "F.Cu")
		(at 210.16214 -371.465094)
		(property "Reference" "PC1"
			(at 0 0 0)
			(layer "F.SilkS")
			(hide yes)
			(effects
				(font
					(size 1.27 1.27)
				)
			)
		)
		(property "Value" ""
			(at 0 0 0)
			(layer "F.Fab")
			(effects
				(font
					(size 1.27 1.27)
				)
			)
		)
		(duplicate_pad_numbers_are_jumpers no)
		(fp_line
			(start -0.7874 -0.4064)
			(end 0.7874 -0.4064)
			(stroke
				(width 0.1524)
				(type default)
			)
			(layer "F.SilkS")
		)
		(fp_line
			(start -0.7874 0.4064)
			(end -0.7874 -0.4064)
			(stroke
				(width 0.1524)
				(type default)
			)
			(layer "F.SilkS")
		)
		(fp_line
			(start 0.7874 -0.4064)
			(end 0.7874 0.4064)
			(stroke
				(width 0.1524)
				(type default)
			)
			(layer "F.SilkS")
		)
		(fp_line
			(start 0.7874 0.4064)
			(end -0.7874 0.4064)
			(stroke
				(width 0.1524)
				(type default)
			)
			(layer "F.SilkS")
		)
		(fp_line
			(start -0.67945 -0.305054)
			(end -0.12065 -0.305054)
			(stroke
				(width 0.1)
				(type default)
			)
			(layer "F.Fab")
		)
		(fp_line
			(start -0.67945 0.3048)
			(end -0.67945 -0.305054)
			(stroke
				(width 0.1)
				(type default)
			)
			(layer "F.Fab")
		)
		(fp_line
			(start -0.12065 -0.305054)
			(end -0.12065 -0.2794)
			(stroke
				(width 0.1)
				(type default)
			)
			(layer "F.Fab")
		)
		(fp_line
			(start -0.12065 -0.2794)
			(end 0.12065 -0.2794)
			(stroke
				(width 0.1)
				(type default)
			)
			(layer "F.Fab")
		)
		(fp_line
			(start -0.12065 0.2794)
			(end -0.12065 0.3048)
			(stroke
				(width 0.1)
				(type default)
			)
			(layer "F.Fab")
		)
		(fp_line
			(start -0.12065 0.3048)
			(end -0.67945 0.3048)
			(stroke
				(width 0.1)
				(type default)
			)
			(layer "F.Fab")
		)
		(fp_line
			(start 0.120396 0.2794)
			(end -0.12065 0.2794)
			(stroke
				(width 0.1)
				(type default)
			)
			(layer "F.Fab")
		)
		(fp_line
			(start 0.120396 0.3048)
			(end 0.120396 0.2794)
			(stroke
				(width 0.1)
				(type default)
			)
			(layer "F.Fab")
		)
		(fp_line
			(start 0.12065 -0.3048)
			(end 0.67945 -0.3048)
			(stroke
				(width 0.1)
				(type default)
			)
			(layer "F.Fab")
		)
		(fp_line
			(start 0.12065 -0.2794)
			(end 0.12065 -0.3048)
			(stroke
				(width 0.1)
				(type default)
			)
			(layer "F.Fab")
		)
		(fp_line
			(start 0.67945 -0.3048)
			(end 0.67945 0.3048)
			(stroke
				(width 0.1)
				(type default)
			)
			(layer "F.Fab")
		)
		(fp_line
			(start 0.67945 0.3048)
			(end 0.120396 0.3048)
			(stroke
				(width 0.1)
				(type default)
			)
			(layer "F.Fab")
		)
		(pad "1" smd circle
			(at -0.40005 0)
			(size 0 0)
			(layers "F.Cu" "F.Mask" "F.Paste")
			(net "P12V_STBY")
		)
		(pad "2" smd circle
			(at 0.40005 0)
			(size 0 0)
			(layers "F.Cu" "F.Mask" "F.Paste")
			(net "GND")
		)
	)
	(footprint ""
		(layer "F.Cu")
		(at 271.895062 -350.098614 90)
		(property "Reference" "C2344"
			(at 0 0 90)
			(layer "F.SilkS")
			(hide yes)
			(effects
				(font
					(size 1.27 1.27)
				)
			)
		)
		(property "Value" ""
			(at 0 0 90)
			(layer "F.Fab")
			(effects
				(font
					(size 1.27 1.27)
				)
			)
		)
		(duplicate_pad_numbers_are_jumpers no)
		(fp_line
			(start 0.299974 -0.150114)
			(end 0.299974 0.150114)
			(stroke
				(width 0.1)
				(type default)
			)
			(layer "F.Fab")
		)
		(fp_line
			(start -0.299974 -0.150114)
			(end 0.299974 -0.150114)
			(stroke
				(width 0.1)
				(type default)
			)
			(layer "F.Fab")
		)
		(fp_line
			(start 0.299974 0.150114)
			(end -0.299974 0.150114)
			(stroke
				(width 0.1)
				(type default)
			)
			(layer "F.Fab")
		)
		(fp_line
			(start -0.299974 0.150114)
			(end -0.299974 -0.150114)
			(stroke
				(width 0.1)
				(type default)
			)
			(layer "F.Fab")
		)
		(pad "1" smd rect
			(at -0.2667 0 90)
			(size 0.3048 0.381)
			(layers "F.Cu" "F.Mask" "F.Paste")
			(net "P5E_PEX2_STN4_TX_DN<78>")
		)
		(pad "2" smd rect
			(at 0.2667 0 90)
			(size 0.3048 0.381)
			(layers "F.Cu" "F.Mask" "F.Paste")
			(net "P5E_PEX2_STN4_TX_C_DN<78>")
		)
	)
	(footprint ""
		(layer "F.Cu")
		(at 96.499426 -112.903508 90)
		(property "Reference" "PC605"
			(at 0 0 90)
			(layer "F.SilkS")
			(hide yes)
			(effects
				(font
					(size 1.27 1.27)
				)
			)
		)
		(property "Value" ""
			(at 0 0 90)
			(layer "F.Fab")
			(effects
				(font
					(size 1.27 1.27)
				)
			)
		)
		(duplicate_pad_numbers_are_jumpers no)
		(fp_line
			(start 1.524 -0.762)
			(end 1.524 0.762)
			(stroke
				(width 0.1524)
				(type default)
			)
			(layer "F.SilkS")
		)
		(fp_line
			(start -1.524 -0.762)
			(end 1.524 -0.762)
			(stroke
				(width 0.1524)
				(type default)
			)
			(layer "F.SilkS")
		)
		(fp_line
			(start 1.524 0.762)
			(end -1.524 0.762)
			(stroke
				(width 0.1524)
				(type default)
			)
			(layer "F.SilkS")
		)
		(fp_line
			(start -1.524 0.762)
			(end -1.524 -0.762)
			(stroke
				(width 0.1524)
				(type default)
			)
			(layer "F.SilkS")
		)
		(fp_line
			(start 1.1049 -0.724916)
			(end -1.1049 -0.724916)
			(stroke
				(width 0.1)
				(type default)
			)
			(layer "F.Fab")
		)
		(fp_line
			(start -1.1049 -0.724916)
			(end -1.1049 0.724916)
			(stroke
				(width 0.1)
				(type default)
			)
			(layer "F.Fab")
		)
		(fp_line
			(start 1.1049 0.724916)
			(end 1.1049 -0.724916)
			(stroke
				(width 0.1)
				(type default)
			)
			(layer "F.Fab")
		)
		(fp_line
			(start -1.1049 0.724916)
			(end 1.1049 0.724916)
			(stroke
				(width 0.1)
				(type default)
			)
			(layer "F.Fab")
		)
		(pad "1" smd rect
			(at -0.889 0 270)
			(size 1.016 1.27)
			(layers "F.Cu" "F.Mask" "F.Paste")
			(net "P12V_NIC1_R")
		)
		(pad "2" smd rect
			(at 0.889 0 270)
			(size 1.016 1.27)
			(layers "F.Cu" "F.Mask" "F.Paste")
			(net "GND")
		)
	)
	(footprint ""
		(layer "F.Cu")
		(at 394.74648 -58.323734)
		(property "Reference" "PC437"
			(at 0 0 0)
			(layer "F.SilkS")
			(hide yes)
			(effects
				(font
					(size 1.27 1.27)
				)
			)
		)
		(property "Value" ""
			(at 0 0 0)
			(layer "F.Fab")
			(effects
				(font
					(size 1.27 1.27)
				)
			)
		)
		(duplicate_pad_numbers_are_jumpers no)
		(fp_line
			(start -1.524 -0.762)
			(end 1.524 -0.762)
			(stroke
				(width 0.1524)
				(type default)
			)
			(layer "F.SilkS")
		)
		(fp_line
			(start -1.524 0.762)
			(end -1.524 -0.762)
			(stroke
				(width 0.1524)
				(type default)
			)
			(layer "F.SilkS")
		)
		(fp_line
			(start 1.524 -0.762)
			(end 1.524 0.762)
			(stroke
				(width 0.1524)
				(type default)
			)
			(layer "F.SilkS")
		)
		(fp_line
			(start 1.524 0.762)
			(end -1.524 0.762)
			(stroke
				(width 0.1524)
				(type default)
			)
			(layer "F.SilkS")
		)
		(fp_line
			(start -1.1049 -0.724916)
			(end -1.1049 0.724916)
			(stroke
				(width 0.1)
				(type default)
			)
			(layer "F.Fab")
		)
		(fp_line
			(start -1.1049 0.724916)
			(end 1.1049 0.724916)
			(stroke
				(width 0.1)
				(type default)
			)
			(layer "F.Fab")
		)
		(fp_line
			(start 1.1049 -0.724916)
			(end -1.1049 -0.724916)
			(stroke
				(width 0.1)
				(type default)
			)
			(layer "F.Fab")
		)
		(fp_line
			(start 1.1049 0.724916)
			(end 1.1049 -0.724916)
			(stroke
				(width 0.1)
				(type default)
			)
			(layer "F.Fab")
		)
		(pad "1" smd rect
			(at -0.889 0 180)
			(size 1.016 1.27)
			(layers "F.Cu" "F.Mask" "F.Paste")
			(net "GND")
		)
		(pad "2" smd rect
			(at 0.889 0 180)
			(size 1.016 1.27)
			(layers "F.Cu" "F.Mask" "F.Paste")
			(net "P12V_AUX")
		)
	)
	(footprint ""
		(layer "F.Cu")
		(at 128.295908 -356.244906 90)
		(property "Reference" "C2274"
			(at 0 0 90)
			(layer "F.SilkS")
			(hide yes)
			(effects
				(font
					(size 1.27 1.27)
				)
			)
		)
		(property "Value" ""
			(at 0 0 90)
			(layer "F.Fab")
			(effects
				(font
					(size 1.27 1.27)
				)
			)
		)
		(duplicate_pad_numbers_are_jumpers no)
		(fp_line
			(start 0.299974 -0.150114)
			(end 0.299974 0.150114)
			(stroke
				(width 0.1)
				(type default)
			)
			(layer "F.Fab")
		)
		(fp_line
			(start -0.299974 -0.150114)
			(end 0.299974 -0.150114)
			(stroke
				(width 0.1)
				(type default)
			)
			(layer "F.Fab")
		)
		(fp_line
			(start 0.299974 0.150114)
			(end -0.299974 0.150114)
			(stroke
				(width 0.1)
				(type default)
			)
			(layer "F.Fab")
		)
		(fp_line
			(start -0.299974 0.150114)
			(end -0.299974 -0.150114)
			(stroke
				(width 0.1)
				(type default)
			)
			(layer "F.Fab")
		)
		(pad "1" smd rect
			(at -0.2667 0 90)
			(size 0.3048 0.381)
			(layers "F.Cu" "F.Mask" "F.Paste")
			(net "P5E_PEX1_STN5_TX_DN<80>")
		)
		(pad "2" smd rect
			(at 0.2667 0 90)
			(size 0.3048 0.381)
			(layers "F.Cu" "F.Mask" "F.Paste")
			(net "P5E_PEX1_STN5_TX_C_DN<80>")
		)
	)
	(footprint ""
		(layer "F.Cu")
		(at 211.892388 -29.139642 180)
		(property "Reference" "C306"
			(at 0 0 180)
			(layer "F.SilkS")
			(hide yes)
			(effects
				(font
					(size 1.27 1.27)
				)
			)
		)
		(property "Value" ""
			(at 0 0 180)
			(layer "F.Fab")
			(effects
				(font
					(size 1.27 1.27)
				)
			)
		)
		(duplicate_pad_numbers_are_jumpers no)
		(fp_line
			(start 0.299974 0.150114)
			(end -0.299974 0.150114)
			(stroke
				(width 0.1)
				(type default)
			)
			(layer "F.Fab")
		)
		(fp_line
			(start 0.299974 -0.150114)
			(end 0.299974 0.150114)
			(stroke
				(width 0.1)
				(type default)
			)
			(layer "F.Fab")
		)
		(fp_line
			(start -0.299974 0.150114)
			(end -0.299974 -0.150114)
			(stroke
				(width 0.1)
				(type default)
			)
			(layer "F.Fab")
		)
		(fp_line
			(start -0.299974 -0.150114)
			(end 0.299974 -0.150114)
			(stroke
				(width 0.1)
				(type default)
			)
			(layer "F.Fab")
		)
		(pad "1" smd rect
			(at -0.2667 0 180)
			(size 0.3048 0.381)
			(layers "F.Cu" "F.Mask" "F.Paste")
			(net "P5E_PEX1_STN2_TX_DP<32>")
		)
		(pad "2" smd rect
			(at 0.2667 0 180)
			(size 0.3048 0.381)
			(layers "F.Cu" "F.Mask" "F.Paste")
			(net "P5E_PEX1_STN2_TX_C_DP<32>")
		)
	)
	(footprint ""
		(layer "F.Cu")
		(at 262.581644 -77.279754 90)
		(property "Reference" "R1076"
			(at 0 0 90)
			(layer "F.SilkS")
			(hide yes)
			(effects
				(font
					(size 1.27 1.27)
				)
			)
		)
		(property "Value" ""
			(at 0 0 90)
			(layer "F.Fab")
			(effects
				(font
					(size 1.27 1.27)
				)
			)
		)
		(duplicate_pad_numbers_are_jumpers no)
		(fp_line
			(start -0.7874 -0.4064)
			(end 0.7874 -0.4064)
			(stroke
				(width 0.1524)
				(type default)
			)
			(layer "F.SilkS")
		)
		(fp_line
			(start -0.12065 -0.305054)
			(end -0.12065 -0.2794)
			(stroke
				(width 0.1)
				(type default)
			)
			(layer "F.Fab")
		)
		(fp_line
			(start -0.67945 -0.305054)
			(end -0.12065 -0.305054)
			(stroke
				(width 0.1)
				(type default)
			)
			(layer "F.Fab")
		)
		(fp_line
			(start 0.67945 -0.3048)
			(end 0.67945 0.3048)
			(stroke
				(width 0.1)
				(type default)
			)
			(layer "F.Fab")
		)
		(fp_line
			(start 0.12065 -0.3048)
			(end 0.67945 -0.3048)
			(stroke
				(width 0.1)
				(type default)
			)
			(layer "F.Fab")
		)
		(fp_line
			(start 0.12065 -0.2794)
			(end 0.12065 -0.3048)
			(stroke
				(width 0.1)
				(type default)
			)
			(layer "F.Fab")
		)
		(fp_line
			(start -0.12065 -0.2794)
			(end 0.12065 -0.2794)
			(stroke
				(width 0.1)
				(type default)
			)
			(layer "F.Fab")
		)
		(fp_line
			(start 0.120396 0.2794)
			(end -0.12065 0.2794)
			(stroke
				(width 0.1)
				(type default)
			)
			(layer "F.Fab")
		)
		(fp_line
			(start -0.12065 0.2794)
			(end -0.12065 0.3048)
			(stroke
				(width 0.1)
				(type default)
			)
			(layer "F.Fab")
		)
		(fp_line
			(start 0.67945 0.3048)
			(end 0.120396 0.3048)
			(stroke
				(width 0.1)
				(type default)
			)
			(layer "F.Fab")
		)
		(fp_line
			(start 0.120396 0.3048)
			(end 0.120396 0.2794)
			(stroke
				(width 0.1)
				(type default)
			)
			(layer "F.Fab")
		)
		(fp_line
			(start -0.12065 0.3048)
			(end -0.67945 0.3048)
			(stroke
				(width 0.1)
				(type default)
			)
			(layer "F.Fab")
		)
		(fp_line
			(start -0.67945 0.3048)
			(end -0.67945 -0.305054)
			(stroke
				(width 0.1)
				(type default)
			)
			(layer "F.Fab")
		)
		(pad "1" smd circle
			(at -0.40005 0 90)
			(size 0 0)
			(layers "F.Cu" "F.Mask" "F.Paste")
			(net "CLK_100M_CK440Q_2_DB800ZL_R_DN")
		)
		(pad "2" smd circle
			(at 0.40005 0 90)
			(size 0 0)
			(layers "F.Cu" "F.Mask" "F.Paste")
			(net "CLK_100M_CK440Q_2_DB800ZL_DN")
		)
	)
)
